FILE_TYPE = CONNECTIVITY;
{Allegro Design Entry HDL 17.2-2016 S081 (4005846) 1/11/2022}
"PAGE_NUMBER" = 84;
0"NC";
1"GND\g";
2"GND\g";
3"GND\g";
4"PWRGD_CPU1_PWROK";
5"RST_PERST_OCP_SFF_N";
6"FM_SMB_RST_E1S_1_N";
7"P3V3_STBY\g";
8"P3V3_STBY\g";
9"P3V3_STBY\g";
10"FM_SMB_RST_E1S_2_N";
11"FM_SMB_RST_E1S_4_N";
12"FM_SMB_RST_E1S_3_N";
13"PWRGD_CPU0_PWROK";
14"FM_SMB_RST_E1S_1_N_R";
15"FM_SMB_RST_E1S_2_N_R";
16"FM_SMB_RST_E1S_3_N_R";
17"FM_SMB_RST_E1S_4_N_R";
18"RST_PERST1_OCP_SFF_N";
19"RST_PERST0_OCP_SFF_N";
20"RST_PERST2_OCP_SFF_N";
21"RST_PERST3_OCP_SFF_N";
22"RST_CPU1_RESETL_N";
23"RST_CPU0_RESETL_N";
24"JTAG_SCM_PLD_TDO";
25"JTAG_SCM_PLD_TDI";
26"JTAG_SCM_PLD_TMS";
27"JTAG_SCM_PLD_TCK";
28"JTAG_PLD_TDO";
29"JTAG_PLD_TCK";
30"JTAG_PLD_TMS";
31"JTAG_PLD_TDI";
32"BMC_HPM_FPGA_LED1_R_N";
33"BMC_HPM_FPGA_LED2_R_N";
34"BMC_HPM_FPGA_LED1";
35"BMC_HPM_FPGA_LED1_N";
36"BMC_HPM_FPGA_LED2_N";
37"BMC_HPM_FPGA_LED2";
38"GND\g";
%"UNIVERSAL_POWER"
"1","(-1775,2475)","2","pure_quanta_power","I1";
;
HDL_POWER"P3V3_STBY"
CDS_LIB"pure_quanta_power";
"A"9;
%"UNIVERSAL_GND"
"1","(-1900,2025)","0","pure_quanta_power","I2";
;
HDL_POWER"GND"
CDS_LIB"pure_quanta_power";
"A"38;
%"Q_RES"
"2","(-6725,5275)","2","pure_quanta","I29";
;
LOCATION"R530"
$SEC"1"
CDS_SEC"1"
PACK_TYPE"0402LF"
VALUE"0"
MATERIAL"CHIP"
PART_NUMBER"CS00002JB38"
TOLERANCE"5%"
WATTAGE"1/16W"
CDS_LIB"pure_quanta";
"A"
$PN"1"23;
"B"
$PN"2"22;
%"Q_CAP"
"1","(-1900,2175)","0","pure_quanta","I3";
;
LOCATION"C20"
$SEC"1"
CDS_SEC"1"
PACK_TYPE"C0402"
VOLTAGE"16V"
PART_NUMBER"CH4103K1B08"
VALUE"0.1UF"
TOLERANCE"10%"
MATERIAL"X7R"
CDS_LIB"pure_quanta";
"B"
$PN"2"38;
"A"
$PN"1"9;
%"Q_RES"
"1","(-7575,2550)","0","pure_quanta","I32";
;
LOCATION"R905"
$SEC"1"
CDS_SEC"1"
VALUE"0"
ROOM"RST_CPU0_PLD_TO_DIMM"
PACK_TYPE"0402LF"
PART_NUMBER"CS00002JB38"
TOLERANCE"5%"
MATERIAL"CHIP"
WATTAGE"1/16W"
BOM_COST"MEM"
CDS_LIB"pure_quanta";
"B"
$PN"2"20;
"A"
$PN"1"5;
%"Q_RES"
"1","(-7575,2500)","0","pure_quanta","I33";
;
LOCATION"R956"
$SEC"1"
CDS_SEC"1"
VALUE"0"
ROOM"RST_CPU0_PLD_TO_DIMM"
PACK_TYPE"0402LF"
PART_NUMBER"CS00002JB38"
TOLERANCE"5%"
MATERIAL"CHIP"
WATTAGE"1/16W"
BOM_COST"MEM"
CDS_LIB"pure_quanta";
"B"
$PN"2"21;
"A"
$PN"1"5;
%"Q_RES"
"1","(-7575,2650)","0","pure_quanta","I34";
;
LOCATION"R877"
$SEC"1"
CDS_SEC"1"
VALUE"0"
ROOM"RST_CPU0_PLD_TO_DIMM"
PACK_TYPE"0402LF"
PART_NUMBER"CS00002JB38"
TOLERANCE"5%"
MATERIAL"CHIP"
WATTAGE"1/16W"
BOM_COST"MEM"
CDS_LIB"pure_quanta";
"B"
$PN"2"19;
"A"
$PN"1"5;
%"Q_RES"
"1","(-7575,2600)","0","pure_quanta","I35";
;
LOCATION"R899"
$SEC"1"
CDS_SEC"1"
VALUE"0"
ROOM"RST_CPU0_PLD_TO_DIMM"
PACK_TYPE"0402LF"
PART_NUMBER"CS00002JB38"
TOLERANCE"5%"
MATERIAL"CHIP"
WATTAGE"1/16W"
BOM_COST"MEM"
CDS_LIB"pure_quanta";
"B"
$PN"2"18;
"A"
$PN"1"5;
%"Q_RES"
"2","(-8450,5275)","2","pure_quanta","I36";
;
LOCATION"R1422"
$SEC"1"
CDS_SEC"1"
VALUE"0"
PACK_TYPE"0402LF"
MATERIAL"CHIP"
PART_NUMBER"CS00002JB38"
TOLERANCE"5%"
WATTAGE"1/16W"
CDS_LIB"pure_quanta";
"A"
$PN"1"13;
"B"
$PN"2"4;
%"CONN8_HBB1081L200D8H"
"1","(-1525,1800)","0","pure_quanta","I4";
;
LOCATION"J57"
$SEC"1"
CDS_SEC"1"
PART_NUMBER"DFHD08MS197"
VALUE"CONN8_HBB1081-L200D-8H"
MATERIAL"IO"
PART_TYPE"THLF"
CDS_LIB"pure_quanta"
NEEDS_NO_SIZE"TRUE"
CDS_LMAN_SYM_OUTLINE"-50,225,50,-225";
"8"
$PN"8"29;
"7"
$PN"7"1;
"6"
$PN"6"30;
"5"
$PN"5"0;
"4"
$PN"4"0;
"3"
$PN"3"28;
"2"
$PN"2"31;
"1"
$PN"1"9;
%"VCC_CORE"
"1","(-7250,1800)","5","pure_quanta_power","I42";
;
HDL_POWER"P3V3_STBY"
CDS_LIB"pure_quanta_power";
"A"8;
%"Q_RES"
"1","(-7675,2025)","0","pure_quanta","I43";
;
LOCATION"R1036"
$SEC"1"
CDS_SEC"1"
VALUE"0"
MATERIAL"CHIP"
PACK_TYPE"0402LF"
PART_NUMBER"CS00002JB38"
TOLERANCE"5%"
WATTAGE"1/16W"
BOM_COST"OCP3.0 "
CDS_LIB"pure_quanta";
"B"
$PN"2"14;
"A"
$PN"1"6;
%"Q_RES"
"1","(-7675,1975)","0","pure_quanta","I44";
;
LOCATION"R1292"
$SEC"1"
CDS_SEC"1"
VALUE"0"
MATERIAL"CHIP"
PACK_TYPE"0402LF"
PART_NUMBER"CS00002JB38"
TOLERANCE"5%"
WATTAGE"1/16W"
BOM_COST"OCP3.0 "
CDS_LIB"pure_quanta";
"B"
$PN"2"15;
"A"
$PN"1"10;
%"Q_RES"
"1","(-7675,1925)","0","pure_quanta","I45";
;
LOCATION"R1301"
$SEC"1"
CDS_SEC"1"
VALUE"0"
MATERIAL"CHIP"
PACK_TYPE"0402LF"
PART_NUMBER"CS00002JB38"
TOLERANCE"5%"
WATTAGE"1/16W"
BOM_COST"OCP3.0 "
CDS_LIB"pure_quanta";
"B"
$PN"2"16;
"A"
$PN"1"12;
%"Q_RES"
"1","(-7675,1875)","0","pure_quanta","I46";
;
LOCATION"R1302"
$SEC"1"
CDS_SEC"1"
VALUE"0"
MATERIAL"CHIP"
PACK_TYPE"0402LF"
PART_NUMBER"CS00002JB38"
TOLERANCE"5%"
WATTAGE"1/16W"
BOM_COST"OCP3.0 "
CDS_LIB"pure_quanta";
"B"
$PN"2"17;
"A"
$PN"1"11;
%"Q_RES"
"1","(-7675,1800)","0","pure_quanta","I47";
;
LOCATION"R1303"
$SEC"1"
CDS_SEC"1"
VALUE"4.7K"
WATTAGE"1/16W"
MATERIAL"CHIP"
TOLERANCE"5%"
PART_NUMBER"TMP_QCS24702JB38"
PACK_TYPE"0402LF"
CDS_LIB"pure_quanta";
"B"
$PN"2"8;
"A"
$PN"1"6;
%"UNIVERSAL_GND"
"1","(-1800,1500)","0","pure_quanta_power","I5";
;
HDL_POWER"GND"
CDS_LIB"pure_quanta_power";
"A"1;
%"UNIVERSAL_GND"
"1","(-1450,4625)","0","pure_quanta_power","I50";
;
HDL_POWER"GND"
CDS_LIB"pure_quanta_power"
BOM_COST"MISC.";
"A"2;
%"Q_LED"
"1","(-2725,5500)","0","pure_quanta","I51";
;
LOCATION"D7"
$SEC"1"
CDS_SEC"1"
PACK_TYPE"SMLF"
COLOR"LED_RED"
PART_NUMBER"BERD0021Z02"
MATERIAL"IC"
MANUF_PN"LTST-C190KRKT"
CDS_LIB"pure_quanta"
NEEDS_NO_SIZE"TRUE";
"A"
$PN"A"33;
"C"
$PN"C"36;
%"MOSFET_DUAL_6P"
"1","(-1850,4800)","6","pure_quanta","I52";
;
LOCATION"Q28"
$SEC"1"
CDS_SEC"1"
PART_NUMBER"BAM70020047"
VALUE"2N7002KDW"
MATERIAL"IC"
PART_TYPE"SMLF"
NEEDS_NO_SIZE"TRUE"
CDS_LMAN_SYM_OUTLINE"-150,100,150,-100"
CDS_LIB"pure_quanta";
"D2"
$PN"3"36;
"D1"
$PN"6"35;
"S2"
$PN"4"2;
"S1"
$PN"1"3;
"G2"
$PN"5"37;
"G1"
$PN"2"34;
%"UNIVERSAL_GND"
"1","(-2225,4625)","0","pure_quanta_power","I53";
;
HDL_POWER"GND"
CDS_LIB"pure_quanta_power"
BOM_COST"MISC.";
"A"3;
%"Q_LED"
"1","(-2700,5150)","0","pure_quanta","I54";
;
LOCATION"D8"
$SEC"1"
CDS_SEC"1"
PACK_TYPE"SMLF"
COLOR"LED_RED"
PART_NUMBER"BERD0021Z02"
MATERIAL"IC"
MANUF_PN"LTST-C190KRKT"
CDS_LIB"pure_quanta"
NEEDS_NO_SIZE"TRUE";
"A"
$PN"A"32;
"C"
$PN"C"35;
%"Q_RES"
"1","(-3875,5500)","0","pure_quanta","I55";
;
LOCATION"R1194"
$SEC"1"
CDS_SEC"1"
PACK_TYPE"0402LF"
PART_NUMBER"CS12002FB06"
VALUE"200"
TOLERANCE"1%"
MATERIAL"CHIP"
WATTAGE"1/16W"
CDS_LIB"pure_quanta";
"B"
$PN"2"33;
"A"
$PN"1"7;
%"Q_RES"
"1","(-3875,5150)","0","pure_quanta","I57";
;
LOCATION"R1266"
$SEC"1"
CDS_SEC"1"
PACK_TYPE"0402LF"
PART_NUMBER"CS12002FB06"
VALUE"200"
TOLERANCE"1%"
MATERIAL"CHIP"
WATTAGE"1/16W"
CDS_LIB"pure_quanta";
"B"
$PN"2"32;
"A"
$PN"1"7;
%"UNIVERSAL_POWER"
"1","(-4100,5750)","0","pure_quanta_power","I58";
;
HDL_POWER"P3V3_STBY"
CDS_LIB"pure_quanta_power"
BOM_COST"OCP3.0 ";
"A"7;
%"Q_RES"
"1","(-2625,1875)","2","pure_quanta","I6";
;
LOCATION"R13"
$SEC"1"
CDS_SEC"1"
VALUE"0"
ROOM"RST_CPU0_PLD_TO_DIMM"
PACK_TYPE"0402LF"
PART_NUMBER"CS00002JB38"
TOLERANCE"5%"
MATERIAL"CHIP"
WATTAGE"1/16W"
CDS_LIB"pure_quanta"
BOM_COST"MEM";
"B"
$PN"2"24;
"A"
$PN"1"28;
%"Q_RES"
"1","(-7675,1750)","0","pure_quanta","I62";
;
LOCATION"R5001"
$SEC"1"
CDS_SEC"1"
VALUE"4.7K"
CDS_LIB"pure_quanta"
PACK_TYPE"0402LF"
PART_NUMBER"TMP_QCS24702JB38"
TOLERANCE"5%"
MATERIAL"CHIP"
WATTAGE"1/16W";
"B"
$PN"2"8;
"A"
$PN"1"10;
%"Q_RES"
"1","(-7675,1700)","0","pure_quanta","I63";
;
LOCATION"R5002"
$SEC"1"
CDS_SEC"1"
VALUE"4.7K"
CDS_LIB"pure_quanta"
WATTAGE"1/16W"
MATERIAL"CHIP"
TOLERANCE"5%"
PART_NUMBER"TMP_QCS24702JB38"
PACK_TYPE"0402LF";
"B"
$PN"2"8;
"A"
$PN"1"12;
%"Q_RES"
"1","(-7675,1650)","0","pure_quanta","I64";
;
LOCATION"R5003"
$SEC"1"
CDS_SEC"1"
VALUE"4.7K"
CDS_LIB"pure_quanta"
WATTAGE"1/16W"
MATERIAL"CHIP"
TOLERANCE"5%"
PART_NUMBER"TMP_QCS24702JB38"
PACK_TYPE"0402LF";
"B"
$PN"2"8;
"A"
$PN"1"11;
%"Q_RES"
"1","(-2625,1925)","2","pure_quanta","I7";
;
LOCATION"R9"
$SEC"1"
CDS_SEC"1"
VALUE"0"
ROOM"RST_CPU0_PLD_TO_DIMM"
PACK_TYPE"0402LF"
PART_NUMBER"CS00002JB38"
TOLERANCE"5%"
MATERIAL"CHIP"
WATTAGE"1/16W"
CDS_LIB"pure_quanta"
BOM_COST"MEM";
"B"
$PN"2"25;
"A"
$PN"1"31;
%"Q_RES"
"1","(-2625,1725)","2","pure_quanta","I8";
;
LOCATION"R14"
$SEC"1"
CDS_SEC"1"
VALUE"0"
ROOM"RST_CPU0_PLD_TO_DIMM"
PACK_TYPE"0402LF"
PART_NUMBER"CS00002JB38"
TOLERANCE"5%"
MATERIAL"CHIP"
WATTAGE"1/16W"
CDS_LIB"pure_quanta"
BOM_COST"MEM";
"B"
$PN"2"26;
"A"
$PN"1"30;
%"Q_RES"
"1","(-2625,1625)","2","pure_quanta","I9";
;
LOCATION"R15"
$SEC"1"
CDS_SEC"1"
VALUE"0"
ROOM"RST_CPU0_PLD_TO_DIMM"
PACK_TYPE"0402LF"
PART_NUMBER"CS00002JB38"
TOLERANCE"5%"
MATERIAL"CHIP"
WATTAGE"1/16W"
BOM_COST"MEM"
CDS_LIB"pure_quanta";
"B"
$PN"2"27;
"A"
$PN"1"29;
END.
